(kicad_pcb
	(version 20221018)
	(generator pcbnew)
	(general
    (thickness 1.7403)
  )
	(paper "A4")
	(title_block
    (title "Data Center RDIMM DDR4 Tester")
    (date "2024-09-30")
    (rev "1.2.4")
		(comment 9 "footprints 1-10 of 690")
	)
	(layers
    (0 "F.Cu" signal)
    (1 "In1.Cu" power)
    (2 "In2.Cu" signal)
    (3 "In3.Cu" power)
    (4 "In4.Cu" power)
    (5 "In5.Cu" signal)
    (6 "In6.Cu" power)
    (7 "In7.Cu" signal)
    (8 "In8.Cu" power)
    (9 "In9.Cu" signal)
    (10 "In10.Cu" power)
    (31 "B.Cu" signal)
    (32 "B.Adhes" user "B.Adhesive")
    (33 "F.Adhes" user "F.Adhesive")
    (34 "B.Paste" user)
    (35 "F.Paste" user)
    (36 "B.SilkS" user "B.Silkscreen")
    (37 "F.SilkS" user "F.Silkscreen")
    (38 "B.Mask" user)
    (39 "F.Mask" user)
    (40 "Dwgs.User" user "User.Drawings")
    (41 "Cmts.User" user "User.Comments")
    (42 "Eco1.User" user "User.Eco1")
    (43 "Eco2.User" user "User.Eco2")
    (44 "Edge.Cuts" user)
    (45 "Margin" user)
    (46 "B.CrtYd" user "B.Courtyard")
    (47 "F.CrtYd" user "F.Courtyard")
    (48 "B.Fab" user)
    (49 "F.Fab" user)
  )
	(footprint "data-center-rdimm-ddr4-tester-footprints:R_0402_1005Metric" (layer "F.Cu")
    (at 238.434 118.271 180)
    (descr "Resistor SMD 0402")
    (tags "resistor SMD 0402")
    (property "Author" "Antmicro")
    (property "DNP" "DNP")
    (property "License" "Apache-2.0")
    (property "MPN" "CR0402-FX-1000GLF")
    (property "Manufacturer" "Bourns")
    (property "Sheetfile" "config-spi.kicad_sch")
    (property "Sheetname" "Config SPI flash")
    (property "Tolerance" "1%")
    (property "Val" "100R")
    (property "dnp" "")
    (property "exclude_from_bom" "")
    (property "ki_description" "100R resistor in 0402 package with 1% tolerance")
    (attr exclude_from_pos_files exclude_from_bom)
    (fp_text reference "R33" (at -0.786 -0.369 180) (layer "F.SilkS")
        (effects (font (size 0.7 0.7) (thickness 0.15)) (justify left bottom))
    )
    (fp_text value "R_100R_0402" (at 0 1.4 180) (layer "F.Fab") hide
        (effects (font (size 0.7 0.7) (thickness 0.15)) (justify left bottom))
    )
    (fp_text user "${REFERENCE}" (at -0.95 3.168 180) (layer "F.Fab") hide
        (effects (font (size 0.7 0.7) (thickness 0.15)) (justify left bottom))
    )
    (fp_text user "License: Apache-2.0" (at -0.95 5.169 180) (layer "F.Fab") hide
        (effects (font (size 0.7 0.7) (thickness 0.15)) (justify left bottom))
    )
    (fp_text user "Author: Antmicro" (at -0.95 4.169 180) (layer "F.Fab") hide
        (effects (font (size 0.7 0.7) (thickness 0.15)) (justify left bottom))
    )
    (fp_rect (start -0.93 -0.47) (end 0.93 0.47)
      (stroke (width 0.05) (type solid)) (fill none) (layer "F.CrtYd"))
    (fp_rect (start -0.5 -0.25) (end 0.5 0.25)
      (stroke (width 0.15) (type solid)) (fill none) (layer "F.Fab"))
    (pad "1" smd roundrect (at -0.485 0 180) (size 0.59 0.64) (layers "F.Cu" "F.Paste" "F.Mask") (roundrect_rratio 0.25)
      (net 143 "3V3_SYS") (pintype "passive"))
    (pad "2" smd roundrect (at 0.485 0 180) (size 0.59 0.64) (layers "F.Cu" "F.Paste" "F.Mask") (roundrect_rratio 0.25)
      (net 96 "CCLK") (pintype "passive"))
  )
	(footprint "data-center-rdimm-ddr4-tester-footprints:R_0402_1005Metric" (layer "F.Cu")
    (at 238.478 119.375)
    (descr "Resistor SMD 0402")
    (tags "resistor SMD 0402")
    (property "Author" "Antmicro")
    (property "DNP" "DNP")
    (property "License" "Apache-2.0")
    (property "MPN" "CR0402-FX-1000GLF")
    (property "Manufacturer" "Bourns")
    (property "Sheetfile" "config-spi.kicad_sch")
    (property "Sheetname" "Config SPI flash")
    (property "Tolerance" "1%")
    (property "Val" "100R")
    (property "dnp" "")
    (property "exclude_from_bom" "")
    (property "ki_description" "100R resistor in 0402 package with 1% tolerance")
    (attr exclude_from_pos_files exclude_from_bom)
    (fp_text reference "R34" (at 0.772 0.225) (layer "F.SilkS")
        (effects (font (size 0.7 0.7) (thickness 0.15)) (justify left bottom))
    )
    (fp_text value "R_100R_0402" (at 0 1.4) (layer "F.Fab") hide
        (effects (font (size 0.7 0.7) (thickness 0.15)) (justify left bottom))
    )
    (fp_text user "Author: Antmicro" (at -0.95 4.169) (layer "F.Fab") hide
        (effects (font (size 0.7 0.7) (thickness 0.15)) (justify left bottom))
    )
    (fp_text user "License: Apache-2.0" (at -0.95 5.169) (layer "F.Fab") hide
        (effects (font (size 0.7 0.7) (thickness 0.15)) (justify left bottom))
    )
    (fp_text user "${REFERENCE}" (at -0.95 3.168) (layer "F.Fab") hide
        (effects (font (size 0.7 0.7) (thickness 0.15)) (justify left bottom))
    )
    (fp_rect (start -0.93 -0.47) (end 0.93 0.47)
      (stroke (width 0.05) (type solid)) (fill none) (layer "F.CrtYd"))
    (fp_rect (start -0.5 -0.25) (end 0.5 0.25)
      (stroke (width 0.15) (type solid)) (fill none) (layer "F.Fab"))
    (pad "1" smd roundrect (at -0.485 0) (size 0.59 0.64) (layers "F.Cu" "F.Paste" "F.Mask") (roundrect_rratio 0.25)
      (net 96 "CCLK") (pintype "passive"))
    (pad "2" smd roundrect (at 0.485 0) (size 0.59 0.64) (layers "F.Cu" "F.Paste" "F.Mask") (roundrect_rratio 0.25)
      (net 9 "GND") (pintype "passive"))
  )
	(footprint "data-center-rdimm-ddr4-tester-footprints:C_0402_1005Metric" (layer "F.Cu")
    (at 235.767 115.731)
    (descr "Capacitor SMD 0402")
    (tags "capacitor SMD 0402")
    (property "Author" "Antmicro")
    (property "Dielectric" "X5R")
    (property "License" "Apache-2.0")
    (property "MPN" "GRM155R61H104KE14D")
    (property "Manufacturer" "Murata")
    (property "Sheetfile" "config-spi.kicad_sch")
    (property "Sheetname" "Config SPI flash")
    (property "Val" "100n")
    (property "Voltage" "50V")
    (property "ki_description" " ")
    (attr smd)
    (fp_text reference "C5" (at -1.037 -3.281) (layer "F.SilkS")
        (effects (font (size 0.7 0.7) (thickness 0.15)) (justify left bottom))
    )
    (fp_text value "C_100n_0402" (at 0 1.4) (layer "F.Fab") hide
        (effects (font (size 0.7 0.7) (thickness 0.15)) (justify left bottom))
    )
    (fp_text user "Author: Antmicro" (at -0.932 4.17) (layer "F.Fab") hide
        (effects (font (size 0.7 0.7) (thickness 0.15)) (justify left bottom))
    )
    (fp_text user "${REFERENCE}" (at -0.932 3.168) (layer "F.Fab") hide
        (effects (font (size 0.7 0.7) (thickness 0.15)) (justify left bottom))
    )
    (fp_text user "License: Apache-2.0" (at -0.932 5.17) (layer "F.Fab") hide
        (effects (font (size 0.7 0.7) (thickness 0.15)) (justify left bottom))
    )
    (fp_rect (start -0.94 -0.47) (end 0.94 0.47)
      (stroke (width 0.05) (type solid)) (fill none) (layer "F.CrtYd"))
    (fp_rect (start -0.499 -0.249) (end 0.499 0.249)
      (stroke (width 0.15) (type solid)) (fill none) (layer "F.Fab"))
    (pad "1" smd roundrect (at -0.484 0) (size 0.59 0.64) (layers "F.Cu" "F.Paste" "F.Mask") (roundrect_rratio 0.25)
      (net 143 "3V3_SYS") (pintype "passive"))
    (pad "2" smd roundrect (at 0.484 0) (size 0.59 0.64) (layers "F.Cu" "F.Paste" "F.Mask") (roundrect_rratio 0.25)
      (net 9 "GND") (pintype "passive"))
  )
	(footprint "data-center-rdimm-ddr4-tester-footprints:C_0402_1005Metric" (layer "F.Cu")
    (at 138.286328 115.108157 180)
    (descr "Capacitor SMD 0402")
    (tags "capacitor SMD 0402")
    (property "Author" "Antmicro")
    (property "Dielectric" "")
    (property "License" "Apache-2.0")
    (property "MPN" "GRM155R61A475MEAAD")
    (property "Manufacturer" "Murata")
    (property "Sheetfile" "interfaces.kicad_sch")
    (property "Sheetname" "Interfaces")
    (property "Val" "4u7")
    (property "Voltage" "")
    (property "ki_description" " ")
    (attr smd)
    (fp_text reference "C189" (at 1.926328 1.709157 180) (layer "F.SilkS")
        (effects (font (size 0.7 0.7) (thickness 0.15)) (justify left bottom))
    )
    (fp_text value "C_4u7_0402" (at 0 1.4 180) (layer "F.Fab") hide
        (effects (font (size 0.7 0.7) (thickness 0.15)) (justify left bottom))
    )
    (fp_text user "${REFERENCE}" (at -0.932 3.168 180) (layer "F.Fab") hide
        (effects (font (size 0.7 0.7) (thickness 0.15)) (justify left bottom))
    )
    (fp_text user "License: Apache-2.0" (at -0.932 5.17 180) (layer "F.Fab") hide
        (effects (font (size 0.7 0.7) (thickness 0.15)) (justify left bottom))
    )
    (fp_text user "Author: Antmicro" (at -0.932 4.17 180) (layer "F.Fab") hide
        (effects (font (size 0.7 0.7) (thickness 0.15)) (justify left bottom))
    )
    (fp_rect (start -0.94 -0.47) (end 0.94 0.47)
      (stroke (width 0.05) (type solid)) (fill none) (layer "F.CrtYd"))
    (fp_rect (start -0.499 -0.249) (end 0.499 0.249)
      (stroke (width 0.15) (type solid)) (fill none) (layer "F.Fab"))
    (pad "1" smd roundrect (at -0.484 0 180) (size 0.59 0.64) (layers "F.Cu" "F.Paste" "F.Mask") (roundrect_rratio 0.25)
      (net 76 "Net-(U7-V_{PHY})") (pintype "passive"))
    (pad "2" smd roundrect (at 0.484 0 180) (size 0.59 0.64) (layers "F.Cu" "F.Paste" "F.Mask") (roundrect_rratio 0.25)
      (net 9 "GND") (pintype "passive"))
  )
	(footprint "data-center-rdimm-ddr4-tester-footprints:C_0402_1005Metric" (layer "F.Cu")
    (at 134.236328 111.897157 -90)
    (descr "Capacitor SMD 0402")
    (tags "capacitor SMD 0402")
    (property "Author" "Antmicro")
    (property "Dielectric" "X5R")
    (property "License" "Apache-2.0")
    (property "MPN" "GRM155R61H104KE14D")
    (property "Manufacturer" "Murata")
    (property "Sheetfile" "interfaces.kicad_sch")
    (property "Sheetname" "Interfaces")
    (property "Val" "100n")
    (property "Voltage" "50V")
    (property "ki_description" " ")
    (attr smd)
    (fp_text reference "C196" (at 1.342843 -1.233672 -90) (layer "F.SilkS")
        (effects (font (size 0.7 0.7) (thickness 0.15)) (justify left bottom))
    )
    (fp_text value "C_100n_0402" (at 0 1.4 -90) (layer "F.Fab") hide
        (effects (font (size 0.7 0.7) (thickness 0.15)) (justify left bottom))
    )
    (fp_text user "${REFERENCE}" (at -0.932 3.168 -90) (layer "F.Fab") hide
        (effects (font (size 0.7 0.7) (thickness 0.15)) (justify left bottom))
    )
    (fp_text user "License: Apache-2.0" (at -0.932 5.17 -90) (layer "F.Fab") hide
        (effects (font (size 0.7 0.7) (thickness 0.15)) (justify left bottom))
    )
    (fp_text user "Author: Antmicro" (at -0.932 4.17 -90) (layer "F.Fab") hide
        (effects (font (size 0.7 0.7) (thickness 0.15)) (justify left bottom))
    )
    (fp_rect (start -0.94 -0.47) (end 0.94 0.47)
      (stroke (width 0.05) (type solid)) (fill none) (layer "F.CrtYd"))
    (fp_rect (start -0.499 -0.249) (end 0.499 0.249)
      (stroke (width 0.15) (type solid)) (fill none) (layer "F.Fab"))
    (pad "1" smd roundrect (at -0.484 0 270) (size 0.59 0.64) (layers "F.Cu" "F.Paste" "F.Mask") (roundrect_rratio 0.25)
      (net 145 "1V8_FT") (pintype "passive"))
    (pad "2" smd roundrect (at 0.484 0 270) (size 0.59 0.64) (layers "F.Cu" "F.Paste" "F.Mask") (roundrect_rratio 0.25)
      (net 9 "GND") (pintype "passive"))
  )
	(footprint "data-center-rdimm-ddr4-tester-footprints:Oscillator_SMD_Geyer_KX-7-4Pin_3.2x2.5mm" (layer "F.Cu")
    (at 135.161328 116.622157 -90)
    (property "Author" "Antmicro")
    (property "License" "Apache-2.0")
    (property "MPN" "ABM8G-12.000MHZ-18-D2Y-T ")
    (property "Manufacturer" "Abracon")
    (property "Sheetfile" "interfaces.kicad_sch")
    (property "Sheetname" "Interfaces")
    (property "Val" "12MHz")
    (attr smd)
    (fp_text reference "Y2" (at 2.797843 1.931328 180) (layer "F.SilkS")
        (effects (font (size 0.7 0.7) (thickness 0.15)) (justify left bottom))
    )
    (fp_text value "Oscillator_SMD_12MHz_KX-7" (at -1.75 2.548 -90) (layer "F.Fab") hide
        (effects (font (size 0.7 0.7) (thickness 0.15)) (justify left bottom))
    )
    (fp_text user "${REFERENCE}" (at -1.75 3.75 -90) (layer "F.Fab") hide
        (effects (font (size 0.7 0.7) (thickness 0.15)) (justify left bottom))
    )
    (fp_text user "Author: Antmicro" (at -1.75 5 -90) (layer "F.Fab") hide
        (effects (font (size 0.7 0.7) (thickness 0.15)) (justify left bottom))
    )
    (fp_text user "License: Apache-2.0" (at -1.75 6.5 -90) (layer "F.Fab") hide
        (effects (font (size 0.7 0.7) (thickness 0.15)) (justify left bottom))
    )
    (fp_line (start -1.6 0.3) (end -1.6 -0.2)
      (stroke (width 0.15) (type solid)) (layer "F.SilkS"))
    (fp_line (start -0.35 -1.25) (end 0.45 -1.25)
      (stroke (width 0.15) (type solid)) (layer "F.SilkS"))
    (fp_line (start -0.35 1.25) (end 0.45 1.25)
      (stroke (width 0.15) (type solid)) (layer "F.SilkS"))
    (fp_line (start 1.6 0.3) (end 1.6 -0.2)
      (stroke (width 0.15) (type solid)) (layer "F.SilkS"))
    (fp_circle (center -1.75 1.5) (end -1.7 1.5)
      (stroke (width 0.15) (type solid)) (fill none) (layer "F.SilkS"))
    (fp_rect (start -1.907 -1.55) (end 2.006 1.649)
      (stroke (width 0.05) (type solid)) (fill none) (layer "F.CrtYd"))
    (pad "1" smd roundrect (at -1.101 0.949 270) (size 1.3 1.1) (layers "F.Cu" "F.Paste" "F.Mask") (roundrect_rratio 0)
      (chamfer_ratio 0.2) (chamfer bottom_left)
      (net 80 "Net-(U7-OSCI)") (pintype "passive"))
    (pad "2" smd rect (at 1.199 0.949 270) (size 1.3 1.1) (layers "F.Cu" "F.Paste" "F.Mask")
      (net 9 "GND") (pinfunction "SH") (pintype "passive"))
    (pad "3" smd rect (at 1.199 -0.85 270) (size 1.3 1.1) (layers "F.Cu" "F.Paste" "F.Mask")
      (net 81 "Net-(U7-OSCO)") (pintype "passive"))
    (pad "4" smd rect (at -1.101 -0.85 270) (size 1.3 1.1) (layers "F.Cu" "F.Paste" "F.Mask")
      (net 9 "GND") (pinfunction "SH") (pintype "passive"))
  )
	(footprint "data-center-rdimm-ddr4-tester-footprints:R_0402_1005Metric" (layer "F.Cu")
    (at 148.051328 107.747157)
    (descr "Resistor SMD 0402")
    (tags "resistor SMD 0402")
    (property "Author" "Antmicro")
    (property "License" "Apache-2.0")
    (property "MPN" "CR0402-FX-22R0GLF")
    (property "Manufacturer" "Bourns")
    (property "Sheetfile" "interfaces.kicad_sch")
    (property "Sheetname" "Interfaces")
    (property "Tolerance" "1%")
    (property "Val" "22R")
    (property "ki_description" "22R resistor in 0402 package with 1% tolerance")
    (attr smd)
    (fp_text reference "R1" (at 0.863672 0.367843) (layer "F.SilkS")
        (effects (font (size 0.7 0.7) (thickness 0.15)) (justify left bottom))
    )
    (fp_text value "R_22R_0402" (at 0 1.4) (layer "F.Fab") hide
        (effects (font (size 0.7 0.7) (thickness 0.15)) (justify left bottom))
    )
    (fp_text user "${REFERENCE}" (at -0.95 3.168) (layer "F.Fab") hide
        (effects (font (size 0.7 0.7) (thickness 0.15)) (justify left bottom))
    )
    (fp_text user "License: Apache-2.0" (at -0.95 5.169) (layer "F.Fab") hide
        (effects (font (size 0.7 0.7) (thickness 0.15)) (justify left bottom))
    )
    (fp_text user "Author: Antmicro" (at -0.95 4.169) (layer "F.Fab") hide
        (effects (font (size 0.7 0.7) (thickness 0.15)) (justify left bottom))
    )
    (fp_rect (start -0.93 -0.47) (end 0.93 0.47)
      (stroke (width 0.05) (type solid)) (fill none) (layer "F.CrtYd"))
    (fp_rect (start -0.5 -0.25) (end 0.5 0.25)
      (stroke (width 0.15) (type solid)) (fill none) (layer "F.Fab"))
    (pad "1" smd roundrect (at -0.485 0) (size 0.59 0.64) (layers "F.Cu" "F.Paste" "F.Mask") (roundrect_rratio 0.25)
      (net 585 "Net-(U7-BDBUS0)") (pintype "passive"))
    (pad "2" smd roundrect (at 0.485 0) (size 0.59 0.64) (layers "F.Cu" "F.Paste" "F.Mask") (roundrect_rratio 0.25)
      (net 126 "AUX_JTAG_TCK") (pintype "passive"))
  )
	(footprint "data-center-rdimm-ddr4-tester-footprints:R_0402_1005Metric" (layer "F.Cu")
    (at 148.036328 106.622157)
    (descr "Resistor SMD 0402")
    (tags "resistor SMD 0402")
    (property "Author" "Antmicro")
    (property "License" "Apache-2.0")
    (property "MPN" "CR0402-FX-22R0GLF")
    (property "Manufacturer" "Bourns")
    (property "Sheetfile" "interfaces.kicad_sch")
    (property "Sheetname" "Interfaces")
    (property "Tolerance" "1%")
    (property "Val" "22R")
    (property "ki_description" "22R resistor in 0402 package with 1% tolerance")
    (attr smd)
    (fp_text reference "R2" (at 0.863672 0.367843) (layer "F.SilkS")
        (effects (font (size 0.7 0.7) (thickness 0.15)) (justify left bottom))
    )
    (fp_text value "R_22R_0402" (at 0 1.4) (layer "F.Fab") hide
        (effects (font (size 0.7 0.7) (thickness 0.15)) (justify left bottom))
    )
    (fp_text user "License: Apache-2.0" (at -0.95 5.169) (layer "F.Fab") hide
        (effects (font (size 0.7 0.7) (thickness 0.15)) (justify left bottom))
    )
    (fp_text user "Author: Antmicro" (at -0.95 4.169) (layer "F.Fab") hide
        (effects (font (size 0.7 0.7) (thickness 0.15)) (justify left bottom))
    )
    (fp_text user "${REFERENCE}" (at -0.95 3.168) (layer "F.Fab") hide
        (effects (font (size 0.7 0.7) (thickness 0.15)) (justify left bottom))
    )
    (fp_rect (start -0.93 -0.47) (end 0.93 0.47)
      (stroke (width 0.05) (type solid)) (fill none) (layer "F.CrtYd"))
    (fp_rect (start -0.5 -0.25) (end 0.5 0.25)
      (stroke (width 0.15) (type solid)) (fill none) (layer "F.Fab"))
    (pad "1" smd roundrect (at -0.485 0) (size 0.59 0.64) (layers "F.Cu" "F.Paste" "F.Mask") (roundrect_rratio 0.25)
      (net 586 "Net-(U7-BDBUS1)") (pintype "passive"))
    (pad "2" smd roundrect (at 0.485 0) (size 0.59 0.64) (layers "F.Cu" "F.Paste" "F.Mask") (roundrect_rratio 0.25)
      (net 128 "AUX_JTAG_TDI") (pintype "passive"))
  )
	(footprint "data-center-rdimm-ddr4-tester-footprints:R_0402_1005Metric" (layer "F.Cu")
    (at 148.036328 105.497157)
    (descr "Resistor SMD 0402")
    (tags "resistor SMD 0402")
    (property "Author" "Antmicro")
    (property "License" "Apache-2.0")
    (property "MPN" "CR0402-FX-22R0GLF")
    (property "Manufacturer" "Bourns")
    (property "Sheetfile" "interfaces.kicad_sch")
    (property "Sheetname" "Interfaces")
    (property "Tolerance" "1%")
    (property "Val" "22R")
    (property "ki_description" "22R resistor in 0402 package with 1% tolerance")
    (attr smd)
    (fp_text reference "R3" (at 0.863672 0.367843) (layer "F.SilkS")
        (effects (font (size 0.7 0.7) (thickness 0.15)) (justify left bottom))
    )
    (fp_text value "R_22R_0402" (at 0 1.4) (layer "F.Fab") hide
        (effects (font (size 0.7 0.7) (thickness 0.15)) (justify left bottom))
    )
    (fp_text user "${REFERENCE}" (at -0.95 3.168) (layer "F.Fab") hide
        (effects (font (size 0.7 0.7) (thickness 0.15)) (justify left bottom))
    )
    (fp_text user "Author: Antmicro" (at -0.95 4.169) (layer "F.Fab") hide
        (effects (font (size 0.7 0.7) (thickness 0.15)) (justify left bottom))
    )
    (fp_text user "License: Apache-2.0" (at -0.95 5.169) (layer "F.Fab") hide
        (effects (font (size 0.7 0.7) (thickness 0.15)) (justify left bottom))
    )
    (fp_rect (start -0.93 -0.47) (end 0.93 0.47)
      (stroke (width 0.05) (type solid)) (fill none) (layer "F.CrtYd"))
    (fp_rect (start -0.5 -0.25) (end 0.5 0.25)
      (stroke (width 0.15) (type solid)) (fill none) (layer "F.Fab"))
    (pad "1" smd roundrect (at -0.485 0) (size 0.59 0.64) (layers "F.Cu" "F.Paste" "F.Mask") (roundrect_rratio 0.25)
      (net 587 "Net-(U7-BDBUS2)") (pintype "passive"))
    (pad "2" smd roundrect (at 0.485 0) (size 0.59 0.64) (layers "F.Cu" "F.Paste" "F.Mask") (roundrect_rratio 0.25)
      (net 146 "AUX_JTAG_TDO") (pintype "passive"))
  )
	(footprint "data-center-rdimm-ddr4-tester-footprints:R_0402_1005Metric" (layer "F.Cu")
    (at 148.036328 102.122157)
    (descr "Resistor SMD 0402")
    (tags "resistor SMD 0402")
    (property "Author" "Antmicro")
    (property "License" "Apache-2.0")
    (property "MPN" "CR0402-FX-22R0GLF")
    (property "Manufacturer" "Bourns")
    (property "Sheetfile" "interfaces.kicad_sch")
    (property "Sheetname" "Interfaces")
    (property "Tolerance" "1%")
    (property "Val" "22R")
    (property "ki_description" "22R resistor in 0402 package with 1% tolerance")
    (attr smd)
    (fp_text reference "R5" (at -0.796328 1.357843) (layer "F.SilkS")
        (effects (font (size 0.7 0.7) (thickness 0.15)) (justify left bottom))
    )
    (fp_text value "R_22R_0402" (at 0 1.4) (layer "F.Fab") hide
        (effects (font (size 0.7 0.7) (thickness 0.15)) (justify left bottom))
    )
    (fp_text user "License: Apache-2.0" (at -0.95 5.169) (layer "F.Fab") hide
        (effects (font (size 0.7 0.7) (thickness 0.15)) (justify left bottom))
    )
    (fp_text user "Author: Antmicro" (at -0.95 4.169) (layer "F.Fab") hide
        (effects (font (size 0.7 0.7) (thickness 0.15)) (justify left bottom))
    )
    (fp_text user "${REFERENCE}" (at -0.95 3.168) (layer "F.Fab") hide
        (effects (font (size 0.7 0.7) (thickness 0.15)) (justify left bottom))
    )
    (fp_rect (start -0.93 -0.47) (end 0.93 0.47)
      (stroke (width 0.05) (type solid)) (fill none) (layer "F.CrtYd"))
    (fp_rect (start -0.5 -0.25) (end 0.5 0.25)
      (stroke (width 0.15) (type solid)) (fill none) (layer "F.Fab"))
    (pad "1" smd roundrect (at -0.485 0) (size 0.59 0.64) (layers "F.Cu" "F.Paste" "F.Mask") (roundrect_rratio 0.25)
      (net 589 "Net-(U7-BDBUS5)") (pintype "passive"))
    (pad "2" smd roundrect (at 0.485 0) (size 0.59 0.64) (layers "F.Cu" "F.Paste" "F.Mask") (roundrect_rratio 0.25)
      (net 133 "AUX_JTAG_RST") (pintype "passive"))
  )
)
